(kicad_pcb
	(version 20260206)
	(generator "pcbnew")
	(generator_version "10.0")
	(general
		(thickness 1.6)
		(legacy_teardrops no)
	)
	(paper "A4")
	(title_block
		(title "01162023_DA0F0TEBIF0_F0T_Expander_BD_F_brd_V02_OCP.brd")
		(comment 1 "Grand Teton / footprints 4009-4015 of 9728")
	)
	(layers
		(0 "F.Cu" signal "TOP")
		(4 "In1.Cu" signal "GND")
		(6 "In2.Cu" signal "VCC")
		(8 "In3.Cu" signal "VCC1")
		(10 "In4.Cu" signal "GND1")
		(12 "In5.Cu" signal "IN1")
		(14 "In6.Cu" signal "GND2")
		(16 "In7.Cu" signal "IN2")
		(18 "In8.Cu" signal "GND3")
		(20 "In9.Cu" signal "IN3")
		(22 "In10.Cu" signal "GND4")
		(24 "In11.Cu" signal "IN4")
		(26 "In12.Cu" signal "GND5")
		(28 "In13.Cu" signal "IN5")
		(30 "In14.Cu" signal "GND6")
		(32 "In15.Cu" signal "IN6")
		(34 "In16.Cu" signal "GND7")
		(2 "B.Cu" signal "BOTTOM")
		(9 "F.Adhes" user "F.Adhesive")
		(11 "B.Adhes" user "B.Adhesive")
		(13 "F.Paste" user "Package Geometry/Pastemask Top")
		(15 "B.Paste" user "Package Geometry/Pastemask Bottom")
		(5 "F.SilkS" user "Ref Des/Silkscreen Top")
		(7 "B.SilkS" user "Ref Des/Silkscreen Bottom")
		(1 "F.Mask" user "Board Geometry/Soldermask Top")
		(3 "B.Mask" user "Board Geometry/Soldermask Bottom")
		(17 "Dwgs.User" user "User.Drawings")
		(19 "Cmts.User" user "User.Comments")
		(21 "Eco1.User" user "User.Eco1")
		(23 "Eco2.User" user "User.Eco2")
		(25 "Edge.Cuts" user "Board Geometry/Outline")
		(27 "Margin" user)
		(31 "F.CrtYd" user "Package Geometry/Place Bound Top")
		(29 "B.CrtYd" user "Package Geometry/Place Bound Bottom")
		(35 "F.Fab" user "Ref Des/Assembly Top")
		(33 "B.Fab" user "Ref Des/Assembly Bottom")
	)
	(footprint ""
		(layer "F.Cu")
		(at 63.008764 -383.576068)
		(property "Reference" "R6301"
			(at 0 0 0)
			(layer "F.SilkS")
			(hide yes)
			(effects
				(font
					(size 1.27 1.27)
				)
			)
		)
		(property "Value" ""
			(at 0 0 0)
			(layer "F.Fab")
			(effects
				(font
					(size 1.27 1.27)
				)
			)
		)
		(duplicate_pad_numbers_are_jumpers no)
		(fp_line
			(start -0.7874 -0.4064)
			(end 0.7874 -0.4064)
			(stroke
				(width 0.1524)
				(type default)
			)
			(layer "F.SilkS")
		)
		(fp_line
			(start -0.7874 0.4064)
			(end -0.7874 -0.4064)
			(stroke
				(width 0.1524)
				(type default)
			)
			(layer "F.SilkS")
		)
		(fp_line
			(start 0.7874 -0.4064)
			(end 0.7874 0.4064)
			(stroke
				(width 0.1524)
				(type default)
			)
			(layer "F.SilkS")
		)
		(fp_line
			(start 0.7874 0.4064)
			(end -0.7874 0.4064)
			(stroke
				(width 0.1524)
				(type default)
			)
			(layer "F.SilkS")
		)
		(fp_line
			(start -0.67945 -0.305054)
			(end -0.12065 -0.305054)
			(stroke
				(width 0.1)
				(type default)
			)
			(layer "F.Fab")
		)
		(fp_line
			(start -0.67945 0.3048)
			(end -0.67945 -0.305054)
			(stroke
				(width 0.1)
				(type default)
			)
			(layer "F.Fab")
		)
		(fp_line
			(start -0.12065 -0.305054)
			(end -0.12065 -0.2794)
			(stroke
				(width 0.1)
				(type default)
			)
			(layer "F.Fab")
		)
		(fp_line
			(start -0.12065 -0.2794)
			(end 0.12065 -0.2794)
			(stroke
				(width 0.1)
				(type default)
			)
			(layer "F.Fab")
		)
		(fp_line
			(start -0.12065 0.2794)
			(end -0.12065 0.3048)
			(stroke
				(width 0.1)
				(type default)
			)
			(layer "F.Fab")
		)
		(fp_line
			(start -0.12065 0.3048)
			(end -0.67945 0.3048)
			(stroke
				(width 0.1)
				(type default)
			)
			(layer "F.Fab")
		)
		(fp_line
			(start 0.120396 0.2794)
			(end -0.12065 0.2794)
			(stroke
				(width 0.1)
				(type default)
			)
			(layer "F.Fab")
		)
		(fp_line
			(start 0.120396 0.3048)
			(end 0.120396 0.2794)
			(stroke
				(width 0.1)
				(type default)
			)
			(layer "F.Fab")
		)
		(fp_line
			(start 0.12065 -0.3048)
			(end 0.67945 -0.3048)
			(stroke
				(width 0.1)
				(type default)
			)
			(layer "F.Fab")
		)
		(fp_line
			(start 0.12065 -0.2794)
			(end 0.12065 -0.3048)
			(stroke
				(width 0.1)
				(type default)
			)
			(layer "F.Fab")
		)
		(fp_line
			(start 0.67945 -0.3048)
			(end 0.67945 0.3048)
			(stroke
				(width 0.1)
				(type default)
			)
			(layer "F.Fab")
		)
		(fp_line
			(start 0.67945 0.3048)
			(end 0.120396 0.3048)
			(stroke
				(width 0.1)
				(type default)
			)
			(layer "F.Fab")
		)
		(pad "1" smd circle
			(at -0.40005 0)
			(size 0 0)
			(layers "F.Cu" "F.Mask" "F.Paste")
			(net "RST_MB_PERST_2_N")
		)
		(pad "2" smd circle
			(at 0.40005 0)
			(size 0 0)
			(layers "F.Cu" "F.Mask" "F.Paste")
			(net "GND")
		)
	)
	(footprint ""
		(layer "F.Cu")
		(at 262.088122 -260.84911 -90)
		(property "Reference" "C3363"
			(at 0 0 270)
			(layer "F.SilkS")
			(hide yes)
			(effects
				(font
					(size 1.27 1.27)
				)
			)
		)
		(property "Value" ""
			(at 0 0 270)
			(layer "F.Fab")
			(effects
				(font
					(size 1.27 1.27)
				)
			)
		)
		(duplicate_pad_numbers_are_jumpers no)
		(fp_line
			(start -1.2954 0.5842)
			(end -1.2954 -0.5842)
			(stroke
				(width 0.1524)
				(type default)
			)
			(layer "F.SilkS")
		)
		(fp_line
			(start 1.2954 0.5842)
			(end -1.2954 0.5842)
			(stroke
				(width 0.1524)
				(type default)
			)
			(layer "F.SilkS")
		)
		(fp_line
			(start -1.2954 -0.5842)
			(end 1.2954 -0.5842)
			(stroke
				(width 0.1524)
				(type default)
			)
			(layer "F.SilkS")
		)
		(fp_line
			(start 1.2954 -0.5842)
			(end 1.2954 0.5842)
			(stroke
				(width 0.1524)
				(type default)
			)
			(layer "F.SilkS")
		)
		(fp_line
			(start -0.8636 0.4572)
			(end -0.8636 0.4064)
			(stroke
				(width 0.1)
				(type default)
			)
			(layer "F.Fab")
		)
		(fp_line
			(start 0.8636 0.4572)
			(end -0.8636 0.4572)
			(stroke
				(width 0.1)
				(type default)
			)
			(layer "F.Fab")
		)
		(fp_line
			(start -1.1938 0.4064)
			(end -1.1938 -0.4064)
			(stroke
				(width 0.1)
				(type default)
			)
			(layer "F.Fab")
		)
		(fp_line
			(start -0.8636 0.4064)
			(end -1.1938 0.4064)
			(stroke
				(width 0.1)
				(type default)
			)
			(layer "F.Fab")
		)
		(fp_line
			(start 0.8636 0.4064)
			(end 0.8636 0.4572)
			(stroke
				(width 0.1)
				(type default)
			)
			(layer "F.Fab")
		)
		(fp_line
			(start 1.1938 0.4064)
			(end 0.8636 0.4064)
			(stroke
				(width 0.1)
				(type default)
			)
			(layer "F.Fab")
		)
		(fp_line
			(start -1.1938 -0.4064)
			(end -0.8636 -0.4064)
			(stroke
				(width 0.1)
				(type default)
			)
			(layer "F.Fab")
		)
		(fp_line
			(start -0.8636 -0.4064)
			(end -0.8636 -0.4572)
			(stroke
				(width 0.1)
				(type default)
			)
			(layer "F.Fab")
		)
		(fp_line
			(start 0.8636 -0.4064)
			(end 1.1938 -0.4064)
			(stroke
				(width 0.1)
				(type default)
			)
			(layer "F.Fab")
		)
		(fp_line
			(start 1.1938 -0.4064)
			(end 1.1938 0.4064)
			(stroke
				(width 0.1)
				(type default)
			)
			(layer "F.Fab")
		)
		(fp_line
			(start -0.8636 -0.4572)
			(end 0.8636 -0.4572)
			(stroke
				(width 0.1)
				(type default)
			)
			(layer "F.Fab")
		)
		(fp_line
			(start 0.8636 -0.4572)
			(end 0.8636 -0.4064)
			(stroke
				(width 0.1)
				(type default)
			)
			(layer "F.Fab")
		)
		(pad "1" smd rect
			(at -0.7366 0 180)
			(size 0.7112 0.8128)
			(layers "F.Cu" "F.Mask" "F.Paste")
			(net "P1V8_PLL0_PEX2")
		)
		(pad "2" smd rect
			(at 0.7366 0 180)
			(size 0.7112 0.8128)
			(layers "F.Cu" "F.Mask" "F.Paste")
			(net "GND")
		)
	)
	(footprint ""
		(layer "F.Cu")
		(at 326.012556 -199.282304)
		(property "Reference" "R4238"
			(at 0 0 0)
			(layer "F.SilkS")
			(hide yes)
			(effects
				(font
					(size 1.27 1.27)
				)
			)
		)
		(property "Value" ""
			(at 0 0 0)
			(layer "F.Fab")
			(effects
				(font
					(size 1.27 1.27)
				)
			)
		)
		(duplicate_pad_numbers_are_jumpers no)
		(fp_line
			(start -0.7874 -0.4064)
			(end 0.7874 -0.4064)
			(stroke
				(width 0.1524)
				(type default)
			)
			(layer "F.SilkS")
		)
		(fp_line
			(start -0.7874 0.4064)
			(end -0.7874 -0.4064)
			(stroke
				(width 0.1524)
				(type default)
			)
			(layer "F.SilkS")
		)
		(fp_line
			(start 0.7874 -0.4064)
			(end 0.7874 0.4064)
			(stroke
				(width 0.1524)
				(type default)
			)
			(layer "F.SilkS")
		)
		(fp_line
			(start 0.7874 0.4064)
			(end -0.7874 0.4064)
			(stroke
				(width 0.1524)
				(type default)
			)
			(layer "F.SilkS")
		)
		(fp_line
			(start -0.67945 -0.305054)
			(end -0.12065 -0.305054)
			(stroke
				(width 0.1)
				(type default)
			)
			(layer "F.Fab")
		)
		(fp_line
			(start -0.67945 0.3048)
			(end -0.67945 -0.305054)
			(stroke
				(width 0.1)
				(type default)
			)
			(layer "F.Fab")
		)
		(fp_line
			(start -0.12065 -0.305054)
			(end -0.12065 -0.2794)
			(stroke
				(width 0.1)
				(type default)
			)
			(layer "F.Fab")
		)
		(fp_line
			(start -0.12065 -0.2794)
			(end 0.12065 -0.2794)
			(stroke
				(width 0.1)
				(type default)
			)
			(layer "F.Fab")
		)
		(fp_line
			(start -0.12065 0.2794)
			(end -0.12065 0.3048)
			(stroke
				(width 0.1)
				(type default)
			)
			(layer "F.Fab")
		)
		(fp_line
			(start -0.12065 0.3048)
			(end -0.67945 0.3048)
			(stroke
				(width 0.1)
				(type default)
			)
			(layer "F.Fab")
		)
		(fp_line
			(start 0.120396 0.2794)
			(end -0.12065 0.2794)
			(stroke
				(width 0.1)
				(type default)
			)
			(layer "F.Fab")
		)
		(fp_line
			(start 0.120396 0.3048)
			(end 0.120396 0.2794)
			(stroke
				(width 0.1)
				(type default)
			)
			(layer "F.Fab")
		)
		(fp_line
			(start 0.12065 -0.3048)
			(end 0.67945 -0.3048)
			(stroke
				(width 0.1)
				(type default)
			)
			(layer "F.Fab")
		)
		(fp_line
			(start 0.12065 -0.2794)
			(end 0.12065 -0.3048)
			(stroke
				(width 0.1)
				(type default)
			)
			(layer "F.Fab")
		)
		(fp_line
			(start 0.67945 -0.3048)
			(end 0.67945 0.3048)
			(stroke
				(width 0.1)
				(type default)
			)
			(layer "F.Fab")
		)
		(fp_line
			(start 0.67945 0.3048)
			(end 0.120396 0.3048)
			(stroke
				(width 0.1)
				(type default)
			)
			(layer "F.Fab")
		)
		(pad "1" smd circle
			(at -0.40005 0)
			(size 0 0)
			(layers "F.Cu" "F.Mask" "F.Paste")
			(net "P3V3_AUX")
		)
		(pad "2" smd circle
			(at 0.40005 0)
			(size 0 0)
			(layers "F.Cu" "F.Mask" "F.Paste")
			(net "IRQ_IOEXP_DBV2_N")
		)
	)
	(footprint ""
		(layer "F.Cu")
		(at 63.54699 -385.561332 180)
		(property "Reference" "C4034"
			(at 0 0 180)
			(layer "F.SilkS")
			(hide yes)
			(effects
				(font
					(size 1.27 1.27)
				)
			)
		)
		(property "Value" ""
			(at 0 0 180)
			(layer "F.Fab")
			(effects
				(font
					(size 1.27 1.27)
				)
			)
		)
		(duplicate_pad_numbers_are_jumpers no)
		(fp_line
			(start 0.7874 0.4064)
			(end -0.7874 0.4064)
			(stroke
				(width 0.1524)
				(type default)
			)
			(layer "F.SilkS")
		)
		(fp_line
			(start 0.7874 -0.4064)
			(end 0.7874 0.4064)
			(stroke
				(width 0.1524)
				(type default)
			)
			(layer "F.SilkS")
		)
		(fp_line
			(start -0.7874 0.4064)
			(end -0.7874 -0.4064)
			(stroke
				(width 0.1524)
				(type default)
			)
			(layer "F.SilkS")
		)
		(fp_line
			(start -0.7874 -0.4064)
			(end 0.7874 -0.4064)
			(stroke
				(width 0.1524)
				(type default)
			)
			(layer "F.SilkS")
		)
		(fp_line
			(start 0.67945 0.3048)
			(end 0.120396 0.3048)
			(stroke
				(width 0.1)
				(type default)
			)
			(layer "F.Fab")
		)
		(fp_line
			(start 0.67945 -0.3048)
			(end 0.67945 0.3048)
			(stroke
				(width 0.1)
				(type default)
			)
			(layer "F.Fab")
		)
		(fp_line
			(start 0.12065 -0.2794)
			(end 0.12065 -0.3048)
			(stroke
				(width 0.1)
				(type default)
			)
			(layer "F.Fab")
		)
		(fp_line
			(start 0.12065 -0.3048)
			(end 0.67945 -0.3048)
			(stroke
				(width 0.1)
				(type default)
			)
			(layer "F.Fab")
		)
		(fp_line
			(start 0.120396 0.3048)
			(end 0.120396 0.2794)
			(stroke
				(width 0.1)
				(type default)
			)
			(layer "F.Fab")
		)
		(fp_line
			(start 0.120396 0.2794)
			(end -0.12065 0.2794)
			(stroke
				(width 0.1)
				(type default)
			)
			(layer "F.Fab")
		)
		(fp_line
			(start -0.12065 0.3048)
			(end -0.67945 0.3048)
			(stroke
				(width 0.1)
				(type default)
			)
			(layer "F.Fab")
		)
		(fp_line
			(start -0.12065 0.2794)
			(end -0.12065 0.3048)
			(stroke
				(width 0.1)
				(type default)
			)
			(layer "F.Fab")
		)
		(fp_line
			(start -0.12065 -0.2794)
			(end 0.12065 -0.2794)
			(stroke
				(width 0.1)
				(type default)
			)
			(layer "F.Fab")
		)
		(fp_line
			(start -0.12065 -0.305054)
			(end -0.12065 -0.2794)
			(stroke
				(width 0.1)
				(type default)
			)
			(layer "F.Fab")
		)
		(fp_line
			(start -0.67945 0.3048)
			(end -0.67945 -0.305054)
			(stroke
				(width 0.1)
				(type default)
			)
			(layer "F.Fab")
		)
		(fp_line
			(start -0.67945 -0.305054)
			(end -0.12065 -0.305054)
			(stroke
				(width 0.1)
				(type default)
			)
			(layer "F.Fab")
		)
		(pad "1" smd circle
			(at -0.40005 0 180)
			(size 0 0)
			(layers "F.Cu" "F.Mask" "F.Paste")
			(net "GND")
		)
		(pad "2" smd circle
			(at 0.40005 0 180)
			(size 0 0)
			(layers "F.Cu" "F.Mask" "F.Paste")
			(net "RST_MB_PERST_1_N")
		)
	)
	(footprint ""
		(layer "F.Cu")
		(at 196.119242 -143.504666 180)
		(property "Reference" "C226"
			(at 0 0 180)
			(layer "F.SilkS")
			(hide yes)
			(effects
				(font
					(size 1.27 1.27)
				)
			)
		)
		(property "Value" ""
			(at 0 0 180)
			(layer "F.Fab")
			(effects
				(font
					(size 1.27 1.27)
				)
			)
		)
		(duplicate_pad_numbers_are_jumpers no)
		(fp_line
			(start 0.299974 0.150114)
			(end -0.299974 0.150114)
			(stroke
				(width 0.1)
				(type default)
			)
			(layer "F.Fab")
		)
		(fp_line
			(start 0.299974 -0.150114)
			(end 0.299974 0.150114)
			(stroke
				(width 0.1)
				(type default)
			)
			(layer "F.Fab")
		)
		(fp_line
			(start -0.299974 0.150114)
			(end -0.299974 -0.150114)
			(stroke
				(width 0.1)
				(type default)
			)
			(layer "F.Fab")
		)
		(fp_line
			(start -0.299974 -0.150114)
			(end 0.299974 -0.150114)
			(stroke
				(width 0.1)
				(type default)
			)
			(layer "F.Fab")
		)
		(pad "1" smd rect
			(at -0.2667 0 180)
			(size 0.3048 0.381)
			(layers "F.Cu" "F.Mask" "F.Paste")
			(net "P5E_PEX1_STN0_TX_DP<8>")
		)
		(pad "2" smd rect
			(at 0.2667 0 180)
			(size 0.3048 0.381)
			(layers "F.Cu" "F.Mask" "F.Paste")
			(net "P5E_PEX1_STN0_TX_C_DP<8>")
		)
	)
	(footprint ""
		(layer "F.Cu")
		(at 332.512162 -236.871256 -90)
		(property "Reference" "R1787"
			(at 0 0 270)
			(layer "F.SilkS")
			(hide yes)
			(effects
				(font
					(size 1.27 1.27)
				)
			)
		)
		(property "Value" ""
			(at 0 0 270)
			(layer "F.Fab")
			(effects
				(font
					(size 1.27 1.27)
				)
			)
		)
		(duplicate_pad_numbers_are_jumpers no)
		(fp_line
			(start -0.7874 0.4064)
			(end -0.7874 -0.4064)
			(stroke
				(width 0.1524)
				(type default)
			)
			(layer "F.SilkS")
		)
		(fp_line
			(start 0.7874 0.4064)
			(end -0.7874 0.4064)
			(stroke
				(width 0.1524)
				(type default)
			)
			(layer "F.SilkS")
		)
		(fp_line
			(start -0.7874 -0.4064)
			(end 0.7874 -0.4064)
			(stroke
				(width 0.1524)
				(type default)
			)
			(layer "F.SilkS")
		)
		(fp_line
			(start 0.7874 -0.4064)
			(end 0.7874 0.4064)
			(stroke
				(width 0.1524)
				(type default)
			)
			(layer "F.SilkS")
		)
		(fp_line
			(start -0.67945 0.3048)
			(end -0.67945 -0.305054)
			(stroke
				(width 0.1)
				(type default)
			)
			(layer "F.Fab")
		)
		(fp_line
			(start -0.12065 0.3048)
			(end -0.67945 0.3048)
			(stroke
				(width 0.1)
				(type default)
			)
			(layer "F.Fab")
		)
		(fp_line
			(start 0.120396 0.3048)
			(end 0.120396 0.2794)
			(stroke
				(width 0.1)
				(type default)
			)
			(layer "F.Fab")
		)
		(fp_line
			(start 0.67945 0.3048)
			(end 0.120396 0.3048)
			(stroke
				(width 0.1)
				(type default)
			)
			(layer "F.Fab")
		)
		(fp_line
			(start -0.12065 0.2794)
			(end -0.12065 0.3048)
			(stroke
				(width 0.1)
				(type default)
			)
			(layer "F.Fab")
		)
		(fp_line
			(start 0.120396 0.2794)
			(end -0.12065 0.2794)
			(stroke
				(width 0.1)
				(type default)
			)
			(layer "F.Fab")
		)
		(fp_line
			(start -0.12065 -0.2794)
			(end 0.12065 -0.2794)
			(stroke
				(width 0.1)
				(type default)
			)
			(layer "F.Fab")
		)
		(fp_line
			(start 0.12065 -0.2794)
			(end 0.12065 -0.3048)
			(stroke
				(width 0.1)
				(type default)
			)
			(layer "F.Fab")
		)
		(fp_line
			(start 0.12065 -0.3048)
			(end 0.67945 -0.3048)
			(stroke
				(width 0.1)
				(type default)
			)
			(layer "F.Fab")
		)
		(fp_line
			(start 0.67945 -0.3048)
			(end 0.67945 0.3048)
			(stroke
				(width 0.1)
				(type default)
			)
			(layer "F.Fab")
		)
		(fp_line
			(start -0.67945 -0.305054)
			(end -0.12065 -0.305054)
			(stroke
				(width 0.1)
				(type default)
			)
			(layer "F.Fab")
		)
		(fp_line
			(start -0.12065 -0.305054)
			(end -0.12065 -0.2794)
			(stroke
				(width 0.1)
				(type default)
			)
			(layer "F.Fab")
		)
		(pad "1" smd circle
			(at -0.40005 0 270)
			(size 0 0)
			(layers "F.Cu" "F.Mask" "F.Paste")
			(net "P3V3_AUX")
		)
		(pad "2" smd circle
			(at 0.40005 0 270)
			(size 0 0)
			(layers "F.Cu" "F.Mask" "F.Paste")
			(net "RST_MB_PERST_1_ISO_R_N")
		)
	)
	(footprint ""
		(layer "F.Cu")
		(at 148.511514 -283.643832 -90)
		(property "Reference" "R4575"
			(at 0 0 270)
			(layer "F.SilkS")
			(hide yes)
			(effects
				(font
					(size 1.27 1.27)
				)
			)
		)
		(property "Value" ""
			(at 0 0 270)
			(layer "F.Fab")
			(effects
				(font
					(size 1.27 1.27)
				)
			)
		)
		(duplicate_pad_numbers_are_jumpers no)
		(fp_line
			(start -0.7874 0.4064)
			(end -0.7874 -0.4064)
			(stroke
				(width 0.1524)
				(type default)
			)
			(layer "F.SilkS")
		)
		(fp_line
			(start 0.7874 0.4064)
			(end -0.7874 0.4064)
			(stroke
				(width 0.1524)
				(type default)
			)
			(layer "F.SilkS")
		)
		(fp_line
			(start -0.7874 -0.4064)
			(end 0.7874 -0.4064)
			(stroke
				(width 0.1524)
				(type default)
			)
			(layer "F.SilkS")
		)
		(fp_line
			(start 0.7874 -0.4064)
			(end 0.7874 0.4064)
			(stroke
				(width 0.1524)
				(type default)
			)
			(layer "F.SilkS")
		)
		(fp_line
			(start -0.67945 0.3048)
			(end -0.67945 -0.305054)
			(stroke
				(width 0.1)
				(type default)
			)
			(layer "F.Fab")
		)
		(fp_line
			(start -0.12065 0.3048)
			(end -0.67945 0.3048)
			(stroke
				(width 0.1)
				(type default)
			)
			(layer "F.Fab")
		)
		(fp_line
			(start 0.120396 0.3048)
			(end 0.120396 0.2794)
			(stroke
				(width 0.1)
				(type default)
			)
			(layer "F.Fab")
		)
		(fp_line
			(start 0.67945 0.3048)
			(end 0.120396 0.3048)
			(stroke
				(width 0.1)
				(type default)
			)
			(layer "F.Fab")
		)
		(fp_line
			(start -0.12065 0.2794)
			(end -0.12065 0.3048)
			(stroke
				(width 0.1)
				(type default)
			)
			(layer "F.Fab")
		)
		(fp_line
			(start 0.120396 0.2794)
			(end -0.12065 0.2794)
			(stroke
				(width 0.1)
				(type default)
			)
			(layer "F.Fab")
		)
		(fp_line
			(start -0.12065 -0.2794)
			(end 0.12065 -0.2794)
			(stroke
				(width 0.1)
				(type default)
			)
			(layer "F.Fab")
		)
		(fp_line
			(start 0.12065 -0.2794)
			(end 0.12065 -0.3048)
			(stroke
				(width 0.1)
				(type default)
			)
			(layer "F.Fab")
		)
		(fp_line
			(start 0.12065 -0.3048)
			(end 0.67945 -0.3048)
			(stroke
				(width 0.1)
				(type default)
			)
			(layer "F.Fab")
		)
		(fp_line
			(start 0.67945 -0.3048)
			(end 0.67945 0.3048)
			(stroke
				(width 0.1)
				(type default)
			)
			(layer "F.Fab")
		)
		(fp_line
			(start -0.67945 -0.305054)
			(end -0.12065 -0.305054)
			(stroke
				(width 0.1)
				(type default)
			)
			(layer "F.Fab")
		)
		(fp_line
			(start -0.12065 -0.305054)
			(end -0.12065 -0.2794)
			(stroke
				(width 0.1)
				(type default)
			)
			(layer "F.Fab")
		)
		(pad "1" smd circle
			(at -0.40005 0 270)
			(size 0 0)
			(layers "F.Cu" "F.Mask" "F.Paste")
			(net "PCEPLL7_VDDA18_PEX1")
		)
		(pad "2" smd circle
			(at 0.40005 0 270)
			(size 0 0)
			(layers "F.Cu" "F.Mask" "F.Paste")
			(net "PCEPLL7_VDDA18_PEX1_R")
		)
	)
)
